# BASEBOARD_FAB2 (Tioga Pass) — schematic netlist excerpt (pin names and nets, part order shuffled) for the footprints in the layout excerpt that follows; sources: Cadence DE-HDL packaged netlist, KiCad conversion of Wiwynn_Tioga_Pass_MB.brd

C4F1  CAP_A  1.0UF 6.3V 10% X6S  pkg 0402V  page 193 : A = P1V8_MCP_CPU1 ; B = GND
R4D26  RES  0.0 5% CHIP  pkg 0402  page 201 : A = P3V3_STBY ; B = VR_PVCCIN_CPU0_VDD
C4G4  CAP  1.0UF 16V 10% X6S  pkg 0402  page 233 : A = VR_FET_SW_P12V_STBY_PVPP_GHJ ; B = GND

(kicad_pcb
	(version 20260206)
	(generator "pcbnew")
	(generator_version "10.0")
	(general
		(thickness 1.6)
		(legacy_teardrops no)
	)
	(paper "A4")
	(title_block
		(title "Wiwynn_Tioga_Pass_MB.brd")
		(comment 1 "Tioga Pass / footprints 854-856 of 4770")
	)
	(layers
		(0 "F.Cu" signal "TOP")
		(4 "In1.Cu" signal "L2GND")
		(6 "In2.Cu" signal "L3")
		(8 "In3.Cu" signal "L4GND")
		(10 "In4.Cu" signal "L5")
		(12 "In5.Cu" signal "L6GND")
		(14 "In6.Cu" signal "L7VCC")
		(16 "In7.Cu" signal "L8VCC")
		(18 "In8.Cu" signal "L9GND")
		(20 "In9.Cu" signal "L10")
		(22 "In10.Cu" signal "L11GND")
		(24 "In11.Cu" signal "L12")
		(26 "In12.Cu" signal "L13GND")
		(2 "B.Cu" signal "BOTTOM")
		(9 "F.Adhes" user "F.Adhesive")
		(11 "B.Adhes" user "B.Adhesive")
		(13 "F.Paste" user "Package Geometry/Pastemask Top")
		(15 "B.Paste" user "Package Geometry/Pastemask Bottom")
		(5 "F.SilkS" user "Ref Des/Silkscreen Top")
		(7 "B.SilkS" user "Ref Des/Silkscreen Bottom")
		(1 "F.Mask" user "Board Geometry/Soldermask Top")
		(3 "B.Mask" user "Board Geometry/Soldermask Bottom")
		(17 "Dwgs.User" user "User.Drawings")
		(19 "Cmts.User" user "User.Comments")
		(21 "Eco1.User" user "User.Eco1")
		(23 "Eco2.User" user "User.Eco2")
		(25 "Edge.Cuts" user "Board Geometry/Outline")
		(27 "Margin" user)
		(31 "F.CrtYd" user "Package Geometry/Place Bound Top")
		(29 "B.CrtYd" user "Package Geometry/Place Bound Bottom")
		(35 "F.Fab" user "Ref Des/Assembly Top")
		(33 "B.Fab" user "Ref Des/Assembly Bottom")
	)
	(footprint ""
		(layer "F.Cu")
		(at 180.2257 -77.31125 90)
		(property "Reference" "R4D26"
			(at 0 0 90)
			(layer "F.SilkS")
			(hide yes)
			(effects
				(font
					(size 1.27 1.27)
				)
			)
		)
		(property "Value" ""
			(at 0 0 90)
			(layer "F.Fab")
			(effects
				(font
					(size 1.27 1.27)
				)
			)
		)
		(duplicate_pad_numbers_are_jumpers no)
		(fp_rect
			(start -0.2794 -0.1016)
			(end 0.2794 0.9906)
			(stroke
				(width 0)
				(type default)
			)
			(fill no)
			(layer "F.CrtYd")
		)
		(fp_line
			(start 0.2794 -0.1016)
			(end -0.2794 -0.1016)
			(stroke
				(width 0.1)
				(type default)
			)
			(layer "F.Fab")
		)
		(fp_line
			(start -0.2794 -0.1016)
			(end -0.2794 0.9906)
			(stroke
				(width 0.1)
				(type default)
			)
			(layer "F.Fab")
		)
		(fp_line
			(start 0.2794 0.9906)
			(end 0.2794 -0.1016)
			(stroke
				(width 0.1)
				(type default)
			)
			(layer "F.Fab")
		)
		(fp_line
			(start -0.2794 0.9906)
			(end 0.2794 0.9906)
			(stroke
				(width 0.1)
				(type default)
			)
			(layer "F.Fab")
		)
		(pad "1" smd rect
			(at 0 0 90)
			(size 0.508 0.508)
			(layers "F.Cu" "F.Mask" "F.Paste")
			(net "P3V3_STBY")
		)
		(pad "2" smd rect
			(at 0 0.889 90)
			(size 0.508 0.508)
			(layers "F.Cu" "F.Mask" "F.Paste")
			(net "VR_PVCCIN_CPU0_VDD")
		)
		(zone
			(layer "F.Cu")
			(hatch none 0.5)
			(connect_pads
				(clearance 0)
			)
			(min_thickness 0.25)
			(keepout
				(tracks not_allowed)
				(vias allowed)
				(pads allowed)
				(copperpour not_allowed)
				(footprints allowed)
			)
			(placement
				(enabled no)
				(sheetname "")
			)
			(fill
				(thermal_gap 0.5)
				(thermal_bridge_width 0.5)
				(island_removal_mode 0)
			)
			(polygon
				(pts
					(xy 180.4797 -77.05725) (xy 180.8607 -77.05725) (xy 180.8607 -77.56525) (xy 180.4797 -77.56525)
				)
			)
		)
		(zone
			(layer "F.Cu")
			(hatch none 0.5)
			(connect_pads
				(clearance 0)
			)
			(min_thickness 0.25)
			(keepout
				(tracks allowed)
				(vias not_allowed)
				(pads allowed)
				(copperpour not_allowed)
				(footprints allowed)
			)
			(placement
				(enabled no)
				(sheetname "")
			)
			(fill
				(thermal_gap 0.5)
				(thermal_bridge_width 0.5)
				(island_removal_mode 0)
			)
			(polygon
				(pts
					(xy 180.4797 -77.05725) (xy 180.8607 -77.05725) (xy 180.8607 -77.56525) (xy 180.4797 -77.56525)
				)
			)
		)
	)
	(footprint ""
		(layer "F.Cu")
		(at 181.991 -12.6365 180)
		(property "Reference" "C4G4"
			(at 0 0 180)
			(layer "F.SilkS")
			(hide yes)
			(effects
				(font
					(size 1.27 1.27)
				)
			)
		)
		(property "Value" ""
			(at 0 0 180)
			(layer "F.Fab")
			(effects
				(font
					(size 1.27 1.27)
				)
			)
		)
		(duplicate_pad_numbers_are_jumpers no)
		(fp_poly
			(pts
				(xy 0.3048 -0.1016) (xy 0.3048 0.9906) (xy -0.3048 0.9906) (xy -0.3048 -0.1016)
			)
			(stroke
				(width 0)
				(type default)
			)
			(fill no)
			(layer "F.CrtYd")
		)
		(fp_line
			(start 0.3048 0.9906)
			(end 0.3048 -0.1016)
			(stroke
				(width 0.1)
				(type default)
			)
			(layer "F.Fab")
		)
		(fp_line
			(start 0.3048 -0.1016)
			(end -0.3048 -0.1016)
			(stroke
				(width 0.1)
				(type default)
			)
			(layer "F.Fab")
		)
		(fp_line
			(start -0.3048 0.9906)
			(end 0.3048 0.9906)
			(stroke
				(width 0.1)
				(type default)
			)
			(layer "F.Fab")
		)
		(fp_line
			(start -0.3048 -0.1016)
			(end -0.3048 0.9906)
			(stroke
				(width 0.1)
				(type default)
			)
			(layer "F.Fab")
		)
		(pad "1" smd rect
			(at 0 0 180)
			(size 0.508 0.508)
			(layers "F.Cu" "F.Mask" "F.Paste")
			(net "VR_FET_SW_P12V_STBY_PVPP_GHJ")
		)
		(pad "2" smd rect
			(at 0 0.889 180)
			(size 0.508 0.508)
			(layers "F.Cu" "F.Mask" "F.Paste")
			(net "GND")
		)
		(zone
			(layer "F.Cu")
			(hatch none 0.5)
			(connect_pads
				(clearance 0)
			)
			(min_thickness 0.25)
			(keepout
				(tracks not_allowed)
				(vias allowed)
				(pads allowed)
				(copperpour not_allowed)
				(footprints allowed)
			)
			(placement
				(enabled no)
				(sheetname "")
			)
			(fill
				(thermal_gap 0.5)
				(thermal_bridge_width 0.5)
				(island_removal_mode 0)
			)
			(polygon
				(pts
					(xy 182.245 -13.2715) (xy 181.737 -13.2715) (xy 181.737 -12.8905) (xy 182.245 -12.8905)
				)
			)
		)
		(zone
			(layer "F.Cu")
			(hatch none 0.5)
			(connect_pads
				(clearance 0)
			)
			(min_thickness 0.25)
			(keepout
				(tracks allowed)
				(vias not_allowed)
				(pads allowed)
				(copperpour not_allowed)
				(footprints allowed)
			)
			(placement
				(enabled no)
				(sheetname "")
			)
			(fill
				(thermal_gap 0.5)
				(thermal_bridge_width 0.5)
				(island_removal_mode 0)
			)
			(polygon
				(pts
					(xy 182.245 -12.8905) (xy 181.737 -12.8905) (xy 181.737 -13.2715) (xy 182.245 -13.2715)
				)
			)
		)
	)
	(footprint ""
		(layer "F.Cu")
		(at 167.00627 -34.9631 90)
		(property "Reference" "C4F1"
			(at 0 0 90)
			(layer "F.SilkS")
			(hide yes)
			(effects
				(font
					(size 1.27 1.27)
				)
			)
		)
		(property "Value" ""
			(at 0 0 90)
			(layer "F.Fab")
			(effects
				(font
					(size 1.27 1.27)
				)
			)
		)
		(duplicate_pad_numbers_are_jumpers no)
		(fp_poly
			(pts
				(xy 0.3048 -0.1016) (xy 0.3048 0.9906) (xy -0.3048 0.9906) (xy -0.3048 -0.1016)
			)
			(stroke
				(width 0)
				(type default)
			)
			(fill no)
			(layer "F.CrtYd")
		)
		(fp_line
			(start 0.3048 -0.1016)
			(end -0.3048 -0.1016)
			(stroke
				(width 0.1)
				(type default)
			)
			(layer "F.Fab")
		)
		(fp_line
			(start -0.3048 -0.1016)
			(end -0.3048 0.9906)
			(stroke
				(width 0.1)
				(type default)
			)
			(layer "F.Fab")
		)
		(fp_line
			(start 0.3048 0.9906)
			(end 0.3048 -0.1016)
			(stroke
				(width 0.1)
				(type default)
			)
			(layer "F.Fab")
		)
		(fp_line
			(start -0.3048 0.9906)
			(end 0.3048 0.9906)
			(stroke
				(width 0.1)
				(type default)
			)
			(layer "F.Fab")
		)
		(pad "1" smd rect
			(at 0 0 90)
			(size 0.508 0.508)
			(layers "F.Cu" "F.Mask" "F.Paste")
			(net "P1V8_MCP_CPU1")
		)
		(pad "2" smd rect
			(at 0 0.889 90)
			(size 0.508 0.508)
			(layers "F.Cu" "F.Mask" "F.Paste")
			(net "GND")
		)
		(zone
			(layer "F.Cu")
			(hatch none 0.5)
			(connect_pads
				(clearance 0)
			)
			(min_thickness 0.25)
			(keepout
				(tracks allowed)
				(vias not_allowed)
				(pads allowed)
				(copperpour not_allowed)
				(footprints allowed)
			)
			(placement
				(enabled no)
				(sheetname "")
			)
			(fill
				(thermal_gap 0.5)
				(thermal_bridge_width 0.5)
				(island_removal_mode 0)
			)
			(polygon
				(pts
					(xy 167.26027 -34.7091) (xy 167.26027 -35.2171) (xy 167.64127 -35.2171) (xy 167.64127 -34.7091)
				)
			)
		)
		(zone
			(layer "F.Cu")
			(hatch none 0.5)
			(connect_pads
				(clearance 0)
			)
			(min_thickness 0.25)
			(keepout
				(tracks not_allowed)
				(vias allowed)
				(pads allowed)
				(copperpour not_allowed)
				(footprints allowed)
			)
			(placement
				(enabled no)
				(sheetname "")
			)
			(fill
				(thermal_gap 0.5)
				(thermal_bridge_width 0.5)
				(island_removal_mode 0)
			)
			(polygon
				(pts
					(xy 167.64127 -34.7091) (xy 167.64127 -35.2171) (xy 167.26027 -35.2171) (xy 167.26027 -34.7091)
				)
			)
		)
	)
)
